(kicad_pcb
	(version 20260206)
	(generator "pcbnew")
	(generator_version "10.0")
	(general
		(thickness 1.6)
		(legacy_teardrops no)
	)
	(paper "A4")
	(title_block
		(title "v1-chassis-manager — T6M_CM_d_v01_1031_1645.brd")
		(comment 1 "Open CloudServer (Microsoft) / footprints 1593-1602 of 2512")
	)
	(layers
		(0 "F.Cu" signal "TOP")
		(4 "In1.Cu" signal "GND1")
		(6 "In2.Cu" signal "IN1")
		(8 "In3.Cu" signal "VCC1")
		(10 "In4.Cu" signal "VCC2")
		(12 "In5.Cu" signal "GND2")
		(14 "In6.Cu" signal "IN2")
		(16 "In7.Cu" signal "IN3")
		(18 "In8.Cu" signal "GND3")
		(2 "B.Cu" signal "BOTTOM")
		(9 "F.Adhes" user "F.Adhesive")
		(11 "B.Adhes" user "B.Adhesive")
		(13 "F.Paste" user "Package Geometry/Pastemask Top")
		(15 "B.Paste" user "Package Geometry/Pastemask Bottom")
		(5 "F.SilkS" user "Ref Des/Silkscreen Top")
		(7 "B.SilkS" user "Ref Des/Silkscreen Bottom")
		(1 "F.Mask" user "Board Geometry/Soldermask Top")
		(3 "B.Mask" user "Board Geometry/Soldermask Bottom")
		(17 "Dwgs.User" user "User.Drawings")
		(19 "Cmts.User" user "User.Comments")
		(21 "Eco1.User" user "User.Eco1")
		(23 "Eco2.User" user "User.Eco2")
		(25 "Edge.Cuts" user "Board Geometry/Outline")
		(27 "Margin" user)
		(31 "F.CrtYd" user "Package Geometry/Place Bound Top")
		(29 "B.CrtYd" user "Package Geometry/Place Bound Bottom")
		(35 "F.Fab" user "Ref Des/Assembly Top")
		(33 "B.Fab" user "Ref Des/Assembly Bottom")
	)
	(footprint ""
		(layer "B.Cu")
		(at 74.38136 -185.698638 -90)
		(property "Reference" "C671"
			(at -3.673094 -0.83312 270)
			(unlocked yes)
			(layer "B.SilkS")
			(effects
				(font
					(size 0.7874 0.5842)
					(thickness 0.1524)
				)
				(justify left mirror)
			)
		)
		(property "Value" ""
			(at 0 0 90)
			(layer "B.Fab")
			(effects
				(font
					(size 1.27 1.27)
				)
				(justify mirror)
			)
		)
		(duplicate_pad_numbers_are_jumpers no)
		(fp_line
			(start -0.7874 0.4064)
			(end 0.7874 0.4064)
			(stroke
				(width 0.1524)
				(type default)
			)
			(layer "B.SilkS")
		)
		(fp_line
			(start 0.7874 0.4064)
			(end 0.7874 -0.4064)
			(stroke
				(width 0.1524)
				(type default)
			)
			(layer "B.SilkS")
		)
		(fp_line
			(start 0 0.381)
			(end 0 -0.381)
			(stroke
				(width 0.1524)
				(type default)
			)
			(layer "B.SilkS")
		)
		(fp_line
			(start -0.7874 -0.4064)
			(end -0.7874 0.4064)
			(stroke
				(width 0.1524)
				(type default)
			)
			(layer "B.SilkS")
		)
		(fp_line
			(start 0.7874 -0.4064)
			(end -0.7874 -0.4064)
			(stroke
				(width 0.1524)
				(type default)
			)
			(layer "B.SilkS")
		)
		(fp_poly
			(pts
				(xy 0.5334 0.254) (xy 0.635 0.254) (xy 0.635 0.2286) (xy 0.635 -0.254) (xy 0.5334 -0.254) (xy 0.5334 -0.2794)
				(xy -0.5334 -0.2794) (xy -0.5334 -0.254) (xy -0.635 -0.254) (xy -0.635 0.254) (xy -0.5334 0.254)
				(xy -0.5334 0.2794) (xy 0.508 0.2794) (xy 0.5334 0.2794)
			)
			(stroke
				(width 0)
				(type default)
			)
			(fill no)
			(layer "B.CrtYd")
		)
		(pad "1" smd rect
			(at -0.40005 0 90)
			(size 0.4572 0.508)
			(layers "B.Cu" "B.Mask" "B.Paste")
			(net "UART_T3_NODE1_RXD")
		)
		(pad "2" smd rect
			(at 0.40005 0 90)
			(size 0.4572 0.508)
			(layers "B.Cu" "B.Mask" "B.Paste")
			(net "GND")
		)
	)
	(footprint ""
		(layer "B.Cu")
		(at 166.79164 -188.19749 -90)
		(property "Reference" "C610"
			(at -0.98171 -0.03429 270)
			(unlocked yes)
			(layer "B.SilkS")
			(effects
				(font
					(size 0.7874 0.5842)
					(thickness 0.1524)
				)
				(justify left mirror)
			)
		)
		(property "Value" ""
			(at 0 0 90)
			(layer "B.Fab")
			(effects
				(font
					(size 1.27 1.27)
				)
				(justify mirror)
			)
		)
		(duplicate_pad_numbers_are_jumpers no)
		(fp_line
			(start -0.7874 0.4064)
			(end 0.7874 0.4064)
			(stroke
				(width 0.1524)
				(type default)
			)
			(layer "B.SilkS")
		)
		(fp_line
			(start 0.7874 0.4064)
			(end 0.7874 -0.4064)
			(stroke
				(width 0.1524)
				(type default)
			)
			(layer "B.SilkS")
		)
		(fp_line
			(start 0 0.381)
			(end 0 -0.381)
			(stroke
				(width 0.1524)
				(type default)
			)
			(layer "B.SilkS")
		)
		(fp_line
			(start -0.7874 -0.4064)
			(end -0.7874 0.4064)
			(stroke
				(width 0.1524)
				(type default)
			)
			(layer "B.SilkS")
		)
		(fp_line
			(start 0.7874 -0.4064)
			(end -0.7874 -0.4064)
			(stroke
				(width 0.1524)
				(type default)
			)
			(layer "B.SilkS")
		)
		(fp_poly
			(pts
				(xy 0.5334 0.254) (xy 0.635 0.254) (xy 0.635 0.2286) (xy 0.635 -0.254) (xy 0.5334 -0.254) (xy 0.5334 -0.2794)
				(xy -0.5334 -0.2794) (xy -0.5334 -0.254) (xy -0.635 -0.254) (xy -0.635 0.254) (xy -0.5334 0.254)
				(xy -0.5334 0.2794) (xy 0.508 0.2794) (xy 0.5334 0.2794)
			)
			(stroke
				(width 0)
				(type default)
			)
			(fill no)
			(layer "B.CrtYd")
		)
		(pad "1" smd rect
			(at -0.40005 0 90)
			(size 0.4572 0.508)
			(layers "B.Cu" "B.Mask" "B.Paste")
			(net "I2C_PDB_R_SCL")
		)
		(pad "2" smd rect
			(at 0.40005 0 90)
			(size 0.4572 0.508)
			(layers "B.Cu" "B.Mask" "B.Paste")
			(net "GND")
		)
	)
	(footprint ""
		(layer "B.Cu")
		(at 26.432256 -155.427172)
		(property "Reference" "C514"
			(at -2.96926 -0.13335 0)
			(unlocked yes)
			(layer "B.SilkS")
			(effects
				(font
					(size 0.7874 0.5842)
					(thickness 0.1524)
				)
				(justify left mirror)
			)
		)
		(property "Value" ""
			(at 0 0 0)
			(layer "B.Fab")
			(effects
				(font
					(size 1.27 1.27)
				)
				(justify mirror)
			)
		)
		(duplicate_pad_numbers_are_jumpers no)
		(fp_line
			(start -0.7874 -0.4064)
			(end -0.7874 0.4064)
			(stroke
				(width 0.1524)
				(type default)
			)
			(layer "B.SilkS")
		)
		(fp_line
			(start -0.7874 0.4064)
			(end 0.7874 0.4064)
			(stroke
				(width 0.1524)
				(type default)
			)
			(layer "B.SilkS")
		)
		(fp_line
			(start 0 0.381)
			(end 0 -0.381)
			(stroke
				(width 0.1524)
				(type default)
			)
			(layer "B.SilkS")
		)
		(fp_line
			(start 0.7874 -0.4064)
			(end -0.7874 -0.4064)
			(stroke
				(width 0.1524)
				(type default)
			)
			(layer "B.SilkS")
		)
		(fp_line
			(start 0.7874 0.4064)
			(end 0.7874 -0.4064)
			(stroke
				(width 0.1524)
				(type default)
			)
			(layer "B.SilkS")
		)
		(fp_poly
			(pts
				(xy 0.5334 0.254) (xy 0.635 0.254) (xy 0.635 0.2286) (xy 0.635 -0.254) (xy 0.5334 -0.254) (xy 0.5334 -0.2794)
				(xy -0.5334 -0.2794) (xy -0.5334 -0.254) (xy -0.635 -0.254) (xy -0.635 0.254) (xy -0.5334 0.254)
				(xy -0.5334 0.2794) (xy 0.508 0.2794) (xy 0.5334 0.2794)
			)
			(stroke
				(width 0)
				(type default)
			)
			(fill no)
			(layer "B.CrtYd")
		)
		(pad "1" smd rect
			(at -0.40005 0 180)
			(size 0.4572 0.508)
			(layers "B.Cu" "B.Mask" "B.Paste")
			(net "P1V9_LAN1")
		)
		(pad "2" smd rect
			(at 0.40005 0 180)
			(size 0.4572 0.508)
			(layers "B.Cu" "B.Mask" "B.Paste")
			(net "GND")
		)
	)
	(footprint ""
		(layer "B.Cu")
		(at 158.48076 -187.872624 -90)
		(property "Reference" "R1224"
			(at -4.565396 4.021074 270)
			(unlocked yes)
			(layer "B.SilkS")
			(effects
				(font
					(size 0.7874 0.5842)
					(thickness 0.1524)
				)
				(justify left mirror)
			)
		)
		(property "Value" ""
			(at 0 0 90)
			(layer "B.Fab")
			(effects
				(font
					(size 1.27 1.27)
				)
				(justify mirror)
			)
		)
		(duplicate_pad_numbers_are_jumpers no)
		(fp_line
			(start -0.7874 0.4064)
			(end 0.7874 0.4064)
			(stroke
				(width 0.1524)
				(type default)
			)
			(layer "B.SilkS")
		)
		(fp_line
			(start 0.7874 0.4064)
			(end 0.7874 -0.4064)
			(stroke
				(width 0.1524)
				(type default)
			)
			(layer "B.SilkS")
		)
		(fp_line
			(start -0.7874 -0.4064)
			(end -0.7874 0.4064)
			(stroke
				(width 0.1524)
				(type default)
			)
			(layer "B.SilkS")
		)
		(fp_line
			(start 0.7874 -0.4064)
			(end -0.7874 -0.4064)
			(stroke
				(width 0.1524)
				(type default)
			)
			(layer "B.SilkS")
		)
		(fp_poly
			(pts
				(xy 0.508 0.2794) (xy 0.508 0.2286) (xy 0.635 0.2286) (xy 0.635 -0.254) (xy 0.5334 -0.254) (xy 0.5334 -0.2794)
				(xy -0.5334 -0.2794) (xy -0.5334 -0.254) (xy -0.635 -0.254) (xy -0.635 0.254) (xy -0.5334 0.254)
				(xy -0.5334 0.2794)
			)
			(stroke
				(width 0)
				(type default)
			)
			(fill no)
			(layer "B.CrtYd")
		)
		(pad "1" smd rect
			(at -0.40005 0 90)
			(size 0.4572 0.508)
			(layers "B.Cu" "B.Mask" "B.Paste")
			(net "FAN6_TACH_R")
		)
		(pad "2" smd rect
			(at 0.40005 0 90)
			(size 0.4572 0.508)
			(layers "B.Cu" "B.Mask" "B.Paste")
			(net "GND")
		)
	)
	(footprint ""
		(layer "B.Cu")
		(at 35.847274 -66.433192 180)
		(property "Reference" "C18"
			(at 2.047494 0.057404 0)
			(unlocked yes)
			(layer "B.SilkS")
			(effects
				(font
					(size 0.7874 0.5842)
					(thickness 0.1524)
				)
				(justify left mirror)
			)
		)
		(property "Value" ""
			(at 0 0 0)
			(layer "B.Fab")
			(effects
				(font
					(size 1.27 1.27)
				)
				(justify mirror)
			)
		)
		(duplicate_pad_numbers_are_jumpers no)
		(fp_line
			(start 0.7874 0.4064)
			(end 0.7874 -0.4064)
			(stroke
				(width 0.1524)
				(type default)
			)
			(layer "B.SilkS")
		)
		(fp_line
			(start 0.7874 -0.4064)
			(end -0.7874 -0.4064)
			(stroke
				(width 0.1524)
				(type default)
			)
			(layer "B.SilkS")
		)
		(fp_line
			(start 0 0.381)
			(end 0 -0.381)
			(stroke
				(width 0.1524)
				(type default)
			)
			(layer "B.SilkS")
		)
		(fp_line
			(start -0.7874 0.4064)
			(end 0.7874 0.4064)
			(stroke
				(width 0.1524)
				(type default)
			)
			(layer "B.SilkS")
		)
		(fp_line
			(start -0.7874 -0.4064)
			(end -0.7874 0.4064)
			(stroke
				(width 0.1524)
				(type default)
			)
			(layer "B.SilkS")
		)
		(fp_poly
			(pts
				(xy 0.5334 0.254) (xy 0.635 0.254) (xy 0.635 0.2286) (xy 0.635 -0.254) (xy 0.5334 -0.254) (xy 0.5334 -0.2794)
				(xy -0.5334 -0.2794) (xy -0.5334 -0.254) (xy -0.635 -0.254) (xy -0.635 0.254) (xy -0.5334 0.254)
				(xy -0.5334 0.2794) (xy 0.508 0.2794) (xy 0.5334 0.2794)
			)
			(stroke
				(width 0)
				(type default)
			)
			(fill no)
			(layer "B.CrtYd")
		)
		(pad "1" smd rect
			(at -0.40005 0)
			(size 0.4572 0.508)
			(layers "B.Cu" "B.Mask" "B.Paste")
			(net "P2E_CPU_NIC2_NODE1_TX_C_DN")
		)
		(pad "2" smd rect
			(at 0.40005 0)
			(size 0.4572 0.508)
			(layers "B.Cu" "B.Mask" "B.Paste")
			(net "P2E_CPU_NIC2_NODE1_TX_DN")
		)
	)
	(footprint ""
		(layer "B.Cu")
		(at 104.408224 -65.148206)
		(property "Reference" "R220"
			(at -4.645914 0.87884 0)
			(unlocked yes)
			(layer "B.SilkS")
			(effects
				(font
					(size 0.7874 0.5842)
					(thickness 0.1524)
				)
				(justify left mirror)
			)
		)
		(property "Value" ""
			(at 0 0 0)
			(layer "B.Fab")
			(effects
				(font
					(size 1.27 1.27)
				)
				(justify mirror)
			)
		)
		(duplicate_pad_numbers_are_jumpers no)
		(fp_line
			(start -0.7874 -0.4064)
			(end -0.7874 0.4064)
			(stroke
				(width 0.1524)
				(type default)
			)
			(layer "B.SilkS")
		)
		(fp_line
			(start -0.7874 0.4064)
			(end 0.7874 0.4064)
			(stroke
				(width 0.1524)
				(type default)
			)
			(layer "B.SilkS")
		)
		(fp_line
			(start 0.7874 -0.4064)
			(end -0.7874 -0.4064)
			(stroke
				(width 0.1524)
				(type default)
			)
			(layer "B.SilkS")
		)
		(fp_line
			(start 0.7874 0.4064)
			(end 0.7874 -0.4064)
			(stroke
				(width 0.1524)
				(type default)
			)
			(layer "B.SilkS")
		)
		(fp_poly
			(pts
				(xy 0.508 0.2794) (xy 0.508 0.2286) (xy 0.635 0.2286) (xy 0.635 -0.254) (xy 0.5334 -0.254) (xy 0.5334 -0.2794)
				(xy -0.5334 -0.2794) (xy -0.5334 -0.254) (xy -0.635 -0.254) (xy -0.635 0.254) (xy -0.5334 0.254)
				(xy -0.5334 0.2794)
			)
			(stroke
				(width 0)
				(type default)
			)
			(fill no)
			(layer "B.CrtYd")
		)
		(pad "1" smd rect
			(at -0.40005 0 180)
			(size 0.4572 0.508)
			(layers "B.Cu" "B.Mask" "B.Paste")
			(net "P3V3_STB_NODE1")
		)
		(pad "2" smd rect
			(at 0.40005 0 180)
			(size 0.4572 0.508)
			(layers "B.Cu" "B.Mask" "B.Paste")
			(net "XDP_CPU_NODE1_PG_RST_R")
		)
	)
	(footprint ""
		(layer "B.Cu")
		(at 150.47976 -187.872624 90)
		(property "Reference" "R957"
			(at 4.565396 -3.28676 270)
			(unlocked yes)
			(layer "B.SilkS")
			(effects
				(font
					(size 0.7874 0.5842)
					(thickness 0.1524)
				)
				(justify left mirror)
			)
		)
		(property "Value" ""
			(at 0 0 90)
			(layer "B.Fab")
			(effects
				(font
					(size 1.27 1.27)
				)
				(justify mirror)
			)
		)
		(duplicate_pad_numbers_are_jumpers no)
		(fp_line
			(start 0.7874 -0.4064)
			(end -0.7874 -0.4064)
			(stroke
				(width 0.1524)
				(type default)
			)
			(layer "B.SilkS")
		)
		(fp_line
			(start -0.7874 -0.4064)
			(end -0.7874 0.4064)
			(stroke
				(width 0.1524)
				(type default)
			)
			(layer "B.SilkS")
		)
		(fp_line
			(start 0.7874 0.4064)
			(end 0.7874 -0.4064)
			(stroke
				(width 0.1524)
				(type default)
			)
			(layer "B.SilkS")
		)
		(fp_line
			(start -0.7874 0.4064)
			(end 0.7874 0.4064)
			(stroke
				(width 0.1524)
				(type default)
			)
			(layer "B.SilkS")
		)
		(fp_poly
			(pts
				(xy 0.508 0.2794) (xy 0.508 0.2286) (xy 0.635 0.2286) (xy 0.635 -0.254) (xy 0.5334 -0.254) (xy 0.5334 -0.2794)
				(xy -0.5334 -0.2794) (xy -0.5334 -0.254) (xy -0.635 -0.254) (xy -0.635 0.254) (xy -0.5334 0.254)
				(xy -0.5334 0.2794)
			)
			(stroke
				(width 0)
				(type default)
			)
			(fill no)
			(layer "B.CrtYd")
		)
		(pad "1" smd rect
			(at -0.40005 0 270)
			(size 0.4572 0.508)
			(layers "B.Cu" "B.Mask" "B.Paste")
			(net "UART_T11_NODE1_RXD")
		)
		(pad "2" smd rect
			(at 0.40005 0 270)
			(size 0.4572 0.508)
			(layers "B.Cu" "B.Mask" "B.Paste")
			(net "UART_T11_NODE1_RXD_R")
		)
	)
	(footprint ""
		(layer "B.Cu")
		(at 148.247354 -178.784504 90)
		(property "Reference" "R742"
			(at 0.380492 2.223008 270)
			(unlocked yes)
			(layer "B.SilkS")
			(effects
				(font
					(size 0.7874 0.5842)
					(thickness 0.1524)
				)
				(justify left mirror)
			)
		)
		(property "Value" ""
			(at 0 0 90)
			(layer "B.Fab")
			(effects
				(font
					(size 1.27 1.27)
				)
				(justify mirror)
			)
		)
		(duplicate_pad_numbers_are_jumpers no)
		(fp_line
			(start 0.7874 -0.4064)
			(end -0.7874 -0.4064)
			(stroke
				(width 0.1524)
				(type default)
			)
			(layer "B.SilkS")
		)
		(fp_line
			(start -0.7874 -0.4064)
			(end -0.7874 0.4064)
			(stroke
				(width 0.1524)
				(type default)
			)
			(layer "B.SilkS")
		)
		(fp_line
			(start 0.7874 0.4064)
			(end 0.7874 -0.4064)
			(stroke
				(width 0.1524)
				(type default)
			)
			(layer "B.SilkS")
		)
		(fp_line
			(start -0.7874 0.4064)
			(end 0.7874 0.4064)
			(stroke
				(width 0.1524)
				(type default)
			)
			(layer "B.SilkS")
		)
		(fp_poly
			(pts
				(xy 0.508 0.2794) (xy 0.508 0.2286) (xy 0.635 0.2286) (xy 0.635 -0.254) (xy 0.5334 -0.254) (xy 0.5334 -0.2794)
				(xy -0.5334 -0.2794) (xy -0.5334 -0.254) (xy -0.635 -0.254) (xy -0.635 0.254) (xy -0.5334 0.254)
				(xy -0.5334 0.2794)
			)
			(stroke
				(width 0)
				(type default)
			)
			(fill no)
			(layer "B.CrtYd")
		)
		(pad "1" smd rect
			(at -0.40005 0 270)
			(size 0.4572 0.508)
			(layers "B.Cu" "B.Mask" "B.Paste")
			(net "T11_NODE2_EN")
		)
		(pad "2" smd rect
			(at 0.40005 0 270)
			(size 0.4572 0.508)
			(layers "B.Cu" "B.Mask" "B.Paste")
			(net "P5V_NODE1")
		)
	)
	(footprint ""
		(layer "B.Cu")
		(at 134.197852 -120.884442 -90)
		(property "Reference" "C11"
			(at 0.541274 1.403604 270)
			(unlocked yes)
			(layer "B.SilkS")
			(effects
				(font
					(size 0.7874 0.5842)
					(thickness 0.1524)
				)
				(justify left mirror)
			)
		)
		(property "Value" ""
			(at 0 0 90)
			(layer "B.Fab")
			(effects
				(font
					(size 1.27 1.27)
				)
				(justify mirror)
			)
		)
		(duplicate_pad_numbers_are_jumpers no)
		(fp_line
			(start -0.7874 0.4064)
			(end 0.7874 0.4064)
			(stroke
				(width 0.1524)
				(type default)
			)
			(layer "B.SilkS")
		)
		(fp_line
			(start 0.7874 0.4064)
			(end 0.7874 -0.4064)
			(stroke
				(width 0.1524)
				(type default)
			)
			(layer "B.SilkS")
		)
		(fp_line
			(start 0 0.381)
			(end 0 -0.381)
			(stroke
				(width 0.1524)
				(type default)
			)
			(layer "B.SilkS")
		)
		(fp_line
			(start -0.7874 -0.4064)
			(end -0.7874 0.4064)
			(stroke
				(width 0.1524)
				(type default)
			)
			(layer "B.SilkS")
		)
		(fp_line
			(start 0.7874 -0.4064)
			(end -0.7874 -0.4064)
			(stroke
				(width 0.1524)
				(type default)
			)
			(layer "B.SilkS")
		)
		(fp_poly
			(pts
				(xy 0.5334 0.254) (xy 0.635 0.254) (xy 0.635 0.2286) (xy 0.635 -0.254) (xy 0.5334 -0.254) (xy 0.5334 -0.2794)
				(xy -0.5334 -0.2794) (xy -0.5334 -0.254) (xy -0.635 -0.254) (xy -0.635 0.254) (xy -0.5334 0.254)
				(xy -0.5334 0.2794) (xy 0.508 0.2794) (xy 0.5334 0.2794)
			)
			(stroke
				(width 0)
				(type default)
			)
			(fill no)
			(layer "B.CrtYd")
		)
		(pad "1" smd rect
			(at -0.40005 0 90)
			(size 0.4572 0.508)
			(layers "B.Cu" "B.Mask" "B.Paste")
			(net "P1V05_CLK_NODE1")
		)
		(pad "2" smd rect
			(at 0.40005 0 90)
			(size 0.4572 0.508)
			(layers "B.Cu" "B.Mask" "B.Paste")
			(net "GND")
		)
	)
	(footprint ""
		(layer "B.Cu")
		(at 129.743708 -115.82146)
		(property "Reference" "C1"
			(at -1.518412 1.218946 0)
			(unlocked yes)
			(layer "B.SilkS")
			(effects
				(font
					(size 0.7874 0.5842)
					(thickness 0.1524)
				)
				(justify mirror)
			)
		)
		(property "Value" ""
			(at 0 0 0)
			(layer "B.Fab")
			(effects
				(font
					(size 1.27 1.27)
				)
				(justify mirror)
			)
		)
		(duplicate_pad_numbers_are_jumpers no)
		(fp_line
			(start -1.2954 -0.5842)
			(end -1.2954 0.5842)
			(stroke
				(width 0.1524)
				(type default)
			)
			(layer "B.SilkS")
		)
		(fp_line
			(start -1.2954 0.5842)
			(end 1.2954 0.5842)
			(stroke
				(width 0.1524)
				(type default)
			)
			(layer "B.SilkS")
		)
		(fp_line
			(start 0 -0.5842)
			(end 0 0.5842)
			(stroke
				(width 0.1524)
				(type default)
			)
			(layer "B.SilkS")
		)
		(fp_line
			(start 1.2954 -0.5842)
			(end -1.2954 -0.5842)
			(stroke
				(width 0.1524)
				(type default)
			)
			(layer "B.SilkS")
		)
		(fp_line
			(start 1.2954 0.5842)
			(end 1.2954 -0.5842)
			(stroke
				(width 0.1524)
				(type default)
			)
			(layer "B.SilkS")
		)
		(fp_poly
			(pts
				(xy -0.8636 -0.4572) (xy -0.8636 -0.3556) (xy -1.143 -0.3556) (xy -1.143 0.3556) (xy -0.8636 0.3556)
				(xy -0.8636 0.4572) (xy 0.8636 0.4572) (xy 0.8636 0.3556) (xy 1.143 0.3556) (xy 1.143 -0.3556) (xy 0.8636 -0.3556)
				(xy 0.8636 -0.4572)
			)
			(stroke
				(width 0)
				(type default)
			)
			(fill no)
			(layer "B.CrtYd")
		)
		(fp_line
			(start -0.884936 -0.504952)
			(end -0.884936 0.504952)
			(stroke
				(width 0.1)
				(type default)
			)
			(layer "B.Fab")
		)
		(fp_line
			(start -0.884936 0.504952)
			(end 0.884936 0.504952)
			(stroke
				(width 0.1)
				(type default)
			)
			(layer "B.Fab")
		)
		(fp_line
			(start 0.884936 -0.504952)
			(end -0.884936 -0.504952)
			(stroke
				(width 0.1)
				(type default)
			)
			(layer "B.Fab")
		)
		(fp_line
			(start 0.884936 0.504952)
			(end 0.884936 -0.504952)
			(stroke
				(width 0.1)
				(type default)
			)
			(layer "B.Fab")
		)
		(pad "1" smd rect
			(at -0.7366 0 90)
			(size 0.7112 0.8128)
			(layers "B.Cu" "B.Mask" "B.Paste")
			(net "P3V3_CLK_NODE1")
		)
		(pad "2" smd rect
			(at 0.7366 0 90)
			(size 0.7112 0.8128)
			(layers "B.Cu" "B.Mask" "B.Paste")
			(net "GND")
		)
	)
)
